(kicad_pcb
	(version 20260206)
	(generator "pcbnew")
	(generator_version "10.0")
	(general
		(thickness 1.6)
		(legacy_teardrops no)
	)
	(paper "A4")
	(title_block
		(title "04192023_DAF0TMB3IC0_F0TG_MB_C_brd_V02_OCP.brd")
		(comment 1 "Grand Teton / footprint 3169 of 8354 (U6016), pads 1-111 of 354")
	)
	(layers
		(0 "F.Cu" signal "TOP")
		(4 "In1.Cu" signal "GND")
		(6 "In2.Cu" signal "IN1")
		(8 "In3.Cu" signal "GND1")
		(10 "In4.Cu" signal "IN2")
		(12 "In5.Cu" signal "GND2")
		(14 "In6.Cu" signal "IN3")
		(16 "In7.Cu" signal "GND3")
		(18 "In8.Cu" signal "VCC")
		(20 "In9.Cu" signal "VCC1")
		(22 "In10.Cu" signal "GND4")
		(24 "In11.Cu" signal "IN4")
		(26 "In12.Cu" signal "GND5")
		(28 "In13.Cu" signal "IN5")
		(30 "In14.Cu" signal "GND6")
		(32 "In15.Cu" signal "IN6")
		(34 "In16.Cu" signal "GND7")
		(2 "B.Cu" signal "BOTTOM")
		(9 "F.Adhes" user "F.Adhesive")
		(11 "B.Adhes" user "B.Adhesive")
		(13 "F.Paste" user "Package Geometry/Pastemask Top")
		(15 "B.Paste" user "Package Geometry/Pastemask Bottom")
		(5 "F.SilkS" user "Ref Des/Silkscreen Top")
		(7 "B.SilkS" user "Ref Des/Silkscreen Bottom")
		(1 "F.Mask" user "Board Geometry/Soldermask Top")
		(3 "B.Mask" user "Board Geometry/Soldermask Bottom")
		(17 "Dwgs.User" user "User.Drawings")
		(19 "Cmts.User" user "User.Comments")
		(21 "Eco1.User" user "User.Eco1")
		(23 "Eco2.User" user "User.Eco2")
		(25 "Edge.Cuts" user "Board Geometry/Outline")
		(27 "Margin" user)
		(31 "F.CrtYd" user "Package Geometry/Place Bound Top")
		(29 "B.CrtYd" user "Package Geometry/Place Bound Bottom")
		(35 "F.Fab" user "Ref Des/Assembly Top")
		(33 "B.Fab" user "Ref Des/Assembly Bottom")
	)
	(footprint ""
		(layer "F.Cu")
		(at 156.0957 -387.342634)
		(property "Reference" "U6016"
			(at -8.08609 -8.07466 0)
			(unlocked yes)
			(layer "F.SilkS")
			(effects
				(font
					(size 0.7874 0.5842)
					(thickness 0.1524)
				)
				(justify left)
			)
		)
		(property "Value" ""
			(at 0 0 0)
			(layer "F.Fab")
			(effects
				(font
					(size 1.27 1.27)
				)
			)
		)
		(duplicate_pad_numbers_are_jumpers no)
		(pad "A1" smd oval
			(at 11.050016 -3.938524)
			(size 0.254 0.3302)
			(layers "F.Cu" "F.Mask" "F.Paste")
			(net "NCF_A1_CPU1_P2_GND")
		)
		(pad "A35" smd oval
			(at 11.050016 3.940048)
			(size 0.254 0.3302)
			(layers "F.Cu" "F.Mask" "F.Paste")
			(net "NCF_CPU1_P2_GND")
		)
		(pad "AA10" smd circle
			(at 7.602728 -1.431798)
			(size 0.381 0.381)
			(layers "F.Cu" "F.Mask" "F.Paste")
			(net "P5E_CPU1_P2_TX_BUF_DN<14>")
		)
		(pad "AA29" smd circle
			(at 7.602728 2.032254)
			(size 0.381 0.381)
			(layers "F.Cu" "F.Mask" "F.Paste")
			(net "P5E_CPU1_P2_RX_DN<14>")
		)
		(pad "AB1" smd oval
			(at 7.450074 -3.938524)
			(size 0.254 0.3302)
			(layers "F.Cu" "F.Mask" "F.Paste")
			(net "P5E_CPU1_P2_RX_BUF_DP<14>")
		)
		(pad "AB35" smd oval
			(at 7.450074 3.940048)
			(size 0.254 0.3302)
			(layers "F.Cu" "F.Mask" "F.Paste")
			(net "P5E_CPU1_P2_TX_C_DP<14>")
		)
		(pad "AC4" smd circle
			(at 7.202678 -2.817368)
			(size 0.381 0.381)
			(layers "F.Cu" "F.Mask" "F.Paste")
			(net "GND")
		)
		(pad "AC13" smd circle
			(at 7.202678 -0.79629)
			(size 0.3048 0.3048)
			(layers "F.Cu" "F.Mask" "F.Paste")
			(net "GND")
		)
		(pad "AC17" smd circle
			(at 7.202678 -0.296164)
			(size 0.3048 0.3048)
			(layers "F.Cu" "F.Mask" "F.Paste")
			(net "P0V9_CPU1_RT2_2A")
		)
		(pad "AC20" smd circle
			(at 7.202678 0.203708)
			(size 0.3048 0.3048)
			(layers "F.Cu" "F.Mask" "F.Paste")
			(net "P0V9_CPU1_RT2_2A")
		)
		(pad "AC22" smd circle
			(at 7.202678 0.703834)
			(size 0.3048 0.3048)
			(layers "F.Cu" "F.Mask" "F.Paste")
			(net "GND")
		)
		(pad "AC32" smd circle
			(at 7.202678 2.724912)
			(size 0.381 0.381)
			(layers "F.Cu" "F.Mask" "F.Paste")
			(net "GND")
		)
		(pad "AD2" smd circle
			(at 7.1501 -3.41884)
			(size 0.3048 0.3048)
			(layers "F.Cu" "F.Mask" "F.Paste")
			(net "GND")
		)
		(pad "AD34" smd circle
			(at 7.1501 3.420364)
			(size 0.3048 0.3048)
			(layers "F.Cu" "F.Mask" "F.Paste")
			(net "GND")
		)
		(pad "AE1" smd oval
			(at 6.849872 -3.938524)
			(size 0.254 0.3302)
			(layers "F.Cu" "F.Mask" "F.Paste")
			(net "GND")
		)
		(pad "AE35" smd oval
			(at 6.849872 3.940048)
			(size 0.254 0.3302)
			(layers "F.Cu" "F.Mask" "F.Paste")
			(net "GND")
		)
		(pad "AF7" smd circle
			(at 6.802628 -2.12471)
			(size 0.381 0.381)
			(layers "F.Cu" "F.Mask" "F.Paste")
			(net "P5E_CPU1_P2_TX_BUF_DP<13>")
		)
		(pad "AF26" smd circle
			(at 6.802628 1.339342)
			(size 0.381 0.381)
			(layers "F.Cu" "F.Mask" "F.Paste")
			(net "P5E_CPU1_P2_RX_DP<13>")
		)
		(pad "AG2" smd circle
			(at 6.549898 -3.41884)
			(size 0.3048 0.3048)
			(layers "F.Cu" "F.Mask" "F.Paste")
			(net "P5E_CPU1_P2_RX_BUF_DN<13>")
		)
		(pad "AG34" smd circle
			(at 6.549898 3.420364)
			(size 0.3048 0.3048)
			(layers "F.Cu" "F.Mask" "F.Paste")
			(net "P5E_CPU1_P2_TX_C_DN<13>")
		)
		(pad "AH10" smd circle
			(at 6.402578 -1.431798)
			(size 0.381 0.381)
			(layers "F.Cu" "F.Mask" "F.Paste")
			(net "P5E_CPU1_P2_TX_BUF_DN<13>")
		)
		(pad "AH29" smd circle
			(at 6.402578 2.032254)
			(size 0.381 0.381)
			(layers "F.Cu" "F.Mask" "F.Paste")
			(net "P5E_CPU1_P2_RX_DN<13>")
		)
		(pad "AJ1" smd oval
			(at 6.249924 -3.938524)
			(size 0.254 0.3302)
			(layers "F.Cu" "F.Mask" "F.Paste")
			(net "P5E_CPU1_P2_RX_BUF_DP<13>")
		)
		(pad "AJ35" smd oval
			(at 6.249924 3.940048)
			(size 0.254 0.3302)
			(layers "F.Cu" "F.Mask" "F.Paste")
			(net "P5E_CPU1_P2_TX_C_DP<13>")
		)
		(pad "AK4" smd circle
			(at 6.002528 -2.817368)
			(size 0.381 0.381)
			(layers "F.Cu" "F.Mask" "F.Paste")
			(net "GND")
		)
		(pad "AK13" smd circle
			(at 6.002528 -0.79629)
			(size 0.3048 0.3048)
			(layers "F.Cu" "F.Mask" "F.Paste")
			(net "GND")
		)
		(pad "AK17" smd circle
			(at 6.002528 -0.296164)
			(size 0.3048 0.3048)
			(layers "F.Cu" "F.Mask" "F.Paste")
			(net "P0V9_CPU1_RT2_2A")
		)
		(pad "AK20" smd circle
			(at 6.002528 0.203708)
			(size 0.3048 0.3048)
			(layers "F.Cu" "F.Mask" "F.Paste")
			(net "P0V9_CPU1_RT2_2A")
		)
		(pad "AK22" smd circle
			(at 6.002528 0.703834)
			(size 0.3048 0.3048)
			(layers "F.Cu" "F.Mask" "F.Paste")
			(net "GND")
		)
		(pad "AK32" smd circle
			(at 6.002528 2.724912)
			(size 0.381 0.381)
			(layers "F.Cu" "F.Mask" "F.Paste")
			(net "GND")
		)
		(pad "AL2" smd circle
			(at 5.94995 -3.41884)
			(size 0.3048 0.3048)
			(layers "F.Cu" "F.Mask" "F.Paste")
			(net "GND")
		)
		(pad "AL34" smd circle
			(at 5.94995 3.420364)
			(size 0.3048 0.3048)
			(layers "F.Cu" "F.Mask" "F.Paste")
			(net "GND")
		)
		(pad "AM1" smd oval
			(at 5.649976 -3.938524)
			(size 0.254 0.3302)
			(layers "F.Cu" "F.Mask" "F.Paste")
			(net "GND")
		)
		(pad "AM35" smd oval
			(at 5.649976 3.940048)
			(size 0.254 0.3302)
			(layers "F.Cu" "F.Mask" "F.Paste")
			(net "GND")
		)
		(pad "AN7" smd circle
			(at 5.602478 -2.12471)
			(size 0.381 0.381)
			(layers "F.Cu" "F.Mask" "F.Paste")
			(net "P5E_CPU1_P2_TX_BUF_DP<12>")
		)
		(pad "AN26" smd circle
			(at 5.602478 1.339342)
			(size 0.381 0.381)
			(layers "F.Cu" "F.Mask" "F.Paste")
			(net "P5E_CPU1_P2_RX_DP<12>")
		)
		(pad "AP2" smd circle
			(at 5.350002 -3.41884)
			(size 0.3048 0.3048)
			(layers "F.Cu" "F.Mask" "F.Paste")
			(net "P5E_CPU1_P2_RX_BUF_DN<12>")
		)
		(pad "AP34" smd circle
			(at 5.350002 3.420364)
			(size 0.3048 0.3048)
			(layers "F.Cu" "F.Mask" "F.Paste")
			(net "P5E_CPU1_P2_TX_C_DN<12>")
		)
		(pad "AR10" smd circle
			(at 5.202682 -1.431798)
			(size 0.381 0.381)
			(layers "F.Cu" "F.Mask" "F.Paste")
			(net "P5E_CPU1_P2_TX_BUF_DN<12>")
		)
		(pad "AR29" smd circle
			(at 5.202682 2.032254)
			(size 0.381 0.381)
			(layers "F.Cu" "F.Mask" "F.Paste")
			(net "P5E_CPU1_P2_RX_DN<12>")
		)
		(pad "AT1" smd oval
			(at 5.050028 -3.938524)
			(size 0.254 0.3302)
			(layers "F.Cu" "F.Mask" "F.Paste")
			(net "P5E_CPU1_P2_RX_BUF_DP<12>")
		)
		(pad "AT35" smd oval
			(at 5.050028 3.940048)
			(size 0.254 0.3302)
			(layers "F.Cu" "F.Mask" "F.Paste")
			(net "P5E_CPU1_P2_TX_C_DP<12>")
		)
		(pad "AU4" smd circle
			(at 4.802632 -2.817368)
			(size 0.381 0.381)
			(layers "F.Cu" "F.Mask" "F.Paste")
			(net "GND")
		)
		(pad "AU13" smd circle
			(at 4.802632 -0.79629)
			(size 0.3048 0.3048)
			(layers "F.Cu" "F.Mask" "F.Paste")
			(net "GND")
		)
		(pad "AU17" smd circle
			(at 4.802632 -0.296164)
			(size 0.3048 0.3048)
			(layers "F.Cu" "F.Mask" "F.Paste")
			(net "P0V9_CPU1_RT2_2A")
		)
		(pad "AU20" smd circle
			(at 4.802632 0.203708)
			(size 0.3048 0.3048)
			(layers "F.Cu" "F.Mask" "F.Paste")
			(net "P0V9_CPU1_RT2_2A")
		)
		(pad "AU22" smd circle
			(at 4.802632 0.703834)
			(size 0.3048 0.3048)
			(layers "F.Cu" "F.Mask" "F.Paste")
			(net "GND")
		)
		(pad "AU32" smd circle
			(at 4.802632 2.724912)
			(size 0.381 0.381)
			(layers "F.Cu" "F.Mask" "F.Paste")
			(net "GND")
		)
		(pad "AV2" smd circle
			(at 4.750054 -3.41884)
			(size 0.3048 0.3048)
			(layers "F.Cu" "F.Mask" "F.Paste")
			(net "GND")
		)
		(pad "AV34" smd circle
			(at 4.750054 3.420364)
			(size 0.3048 0.3048)
			(layers "F.Cu" "F.Mask" "F.Paste")
			(net "GND")
		)
		(pad "AW1" smd oval
			(at 4.45008 -3.938524)
			(size 0.254 0.3302)
			(layers "F.Cu" "F.Mask" "F.Paste")
			(net "GND")
		)
		(pad "AW35" smd oval
			(at 4.45008 3.940048)
			(size 0.254 0.3302)
			(layers "F.Cu" "F.Mask" "F.Paste")
			(net "GND")
		)
		(pad "AY7" smd circle
			(at 4.402582 -2.12471)
			(size 0.381 0.381)
			(layers "F.Cu" "F.Mask" "F.Paste")
			(net "P5E_CPU1_P2_TX_BUF_DP<11>")
		)
		(pad "AY26" smd circle
			(at 4.402582 1.339342)
			(size 0.381 0.381)
			(layers "F.Cu" "F.Mask" "F.Paste")
			(net "P5E_CPU1_P2_RX_DP<11>")
		)
		(pad "B3" smd oval
			(at 10.885932 -2.888488 90)
			(size 0.254 0.3302)
			(layers "F.Cu" "F.Mask" "F.Paste")
			(net "JTAG_TCK_RT_CPU1_P2")
		)
		(pad "B6" smd oval
			(at 10.885932 -2.288286 90)
			(size 0.254 0.3302)
			(layers "F.Cu" "F.Mask" "F.Paste")
			(net "JTAG_TDI_RT_CPU1_P2")
		)
		(pad "B9" smd oval
			(at 10.885932 -1.688338 90)
			(size 0.254 0.3302)
			(layers "F.Cu" "F.Mask" "F.Paste")
			(net "JTAG_TDO_RT_CPU1_P2")
		)
		(pad "B12" smd oval
			(at 10.885932 -1.08839 90)
			(size 0.254 0.3302)
			(layers "F.Cu" "F.Mask" "F.Paste")
			(net "JTAG_TMS_RT_CPU1_P2")
		)
		(pad "B16" smd oval
			(at 10.885932 -0.488442 90)
			(size 0.254 0.3302)
			(layers "F.Cu" "F.Mask" "F.Paste")
			(net "Net_2225")
		)
		(pad "B19" smd oval
			(at 10.885932 0.111506 90)
			(size 0.254 0.3302)
			(layers "F.Cu" "F.Mask" "F.Paste")
			(net "GND")
		)
		(pad "B23" smd oval
			(at 10.885932 0.711708 90)
			(size 0.254 0.3302)
			(layers "F.Cu" "F.Mask" "F.Paste")
			(net "RT_CPU1_P2_ADDR2")
		)
		(pad "B25" smd oval
			(at 10.885932 1.311656 90)
			(size 0.254 0.3302)
			(layers "F.Cu" "F.Mask" "F.Paste")
			(net "RT_CPU1_P2_ADDR3")
		)
		(pad "B28" smd oval
			(at 10.885932 1.911604 90)
			(size 0.254 0.3302)
			(layers "F.Cu" "F.Mask" "F.Paste")
			(net "SMB_RT_CPU1_P2_R2_SDA")
		)
		(pad "B31" smd oval
			(at 10.885932 2.511552 90)
			(size 0.254 0.3302)
			(layers "F.Cu" "F.Mask" "F.Paste")
			(net "SMB_RT_CPU1_P2_R2_SCL")
		)
		(pad "BA2" smd circle
			(at 4.150106 -3.41884)
			(size 0.3048 0.3048)
			(layers "F.Cu" "F.Mask" "F.Paste")
			(net "P5E_CPU1_P2_RX_BUF_DN<11>")
		)
		(pad "BA34" smd circle
			(at 4.150106 3.420364)
			(size 0.3048 0.3048)
			(layers "F.Cu" "F.Mask" "F.Paste")
			(net "P5E_CPU1_P2_TX_C_DN<11>")
		)
		(pad "BB10" smd circle
			(at 4.002532 -1.431798)
			(size 0.381 0.381)
			(layers "F.Cu" "F.Mask" "F.Paste")
			(net "P5E_CPU1_P2_TX_BUF_DN<11>")
		)
		(pad "BB29" smd circle
			(at 4.002532 2.032254)
			(size 0.381 0.381)
			(layers "F.Cu" "F.Mask" "F.Paste")
			(net "P5E_CPU1_P2_RX_DN<11>")
		)
		(pad "BC1" smd oval
			(at 3.849878 -3.938524)
			(size 0.254 0.3302)
			(layers "F.Cu" "F.Mask" "F.Paste")
			(net "P5E_CPU1_P2_RX_BUF_DP<11>")
		)
		(pad "BC35" smd oval
			(at 3.849878 3.940048)
			(size 0.254 0.3302)
			(layers "F.Cu" "F.Mask" "F.Paste")
			(net "P5E_CPU1_P2_TX_C_DP<11>")
		)
		(pad "BD4" smd circle
			(at 3.602482 -2.817368)
			(size 0.381 0.381)
			(layers "F.Cu" "F.Mask" "F.Paste")
			(net "GND")
		)
		(pad "BD13" smd circle
			(at 3.602482 -0.79629)
			(size 0.3048 0.3048)
			(layers "F.Cu" "F.Mask" "F.Paste")
			(net "GND")
		)
		(pad "BD17" smd circle
			(at 3.602482 -0.296164)
			(size 0.3048 0.3048)
			(layers "F.Cu" "F.Mask" "F.Paste")
			(net "P0V9_CPU1_RT2_2A_2D")
		)
		(pad "BD20" smd circle
			(at 3.602482 0.203708)
			(size 0.3048 0.3048)
			(layers "F.Cu" "F.Mask" "F.Paste")
			(net "P0V9_CPU1_RT2_2A_2D")
		)
		(pad "BD22" smd circle
			(at 3.602482 0.703834)
			(size 0.3048 0.3048)
			(layers "F.Cu" "F.Mask" "F.Paste")
			(net "GND")
		)
		(pad "BD32" smd circle
			(at 3.602482 2.724912)
			(size 0.381 0.381)
			(layers "F.Cu" "F.Mask" "F.Paste")
			(net "GND")
		)
		(pad "BE2" smd circle
			(at 3.549904 -3.41884)
			(size 0.3048 0.3048)
			(layers "F.Cu" "F.Mask" "F.Paste")
			(net "GND")
		)
		(pad "BE34" smd circle
			(at 3.549904 3.420364)
			(size 0.3048 0.3048)
			(layers "F.Cu" "F.Mask" "F.Paste")
			(net "GND")
		)
		(pad "BF1" smd oval
			(at 3.24993 -3.938524)
			(size 0.254 0.3302)
			(layers "F.Cu" "F.Mask" "F.Paste")
			(net "GND")
		)
		(pad "BF35" smd oval
			(at 3.24993 3.940048)
			(size 0.254 0.3302)
			(layers "F.Cu" "F.Mask" "F.Paste")
			(net "GND")
		)
		(pad "BG7" smd circle
			(at 3.202686 -2.12471)
			(size 0.381 0.381)
			(layers "F.Cu" "F.Mask" "F.Paste")
			(net "P5E_CPU1_P2_TX_BUF_DP<10>")
		)
		(pad "BG26" smd circle
			(at 3.202686 1.339342)
			(size 0.381 0.381)
			(layers "F.Cu" "F.Mask" "F.Paste")
			(net "P5E_CPU1_P2_RX_DP<10>")
		)
		(pad "BH2" smd circle
			(at 2.949956 -3.41884)
			(size 0.3048 0.3048)
			(layers "F.Cu" "F.Mask" "F.Paste")
			(net "P5E_CPU1_P2_RX_BUF_DN<10>")
		)
		(pad "BH34" smd circle
			(at 2.949956 3.420364)
			(size 0.3048 0.3048)
			(layers "F.Cu" "F.Mask" "F.Paste")
			(net "P5E_CPU1_P2_TX_C_DN<10>")
		)
		(pad "BJ10" smd circle
			(at 2.802636 -1.431798)
			(size 0.381 0.381)
			(layers "F.Cu" "F.Mask" "F.Paste")
			(net "P5E_CPU1_P2_TX_BUF_DN<10>")
		)
		(pad "BJ29" smd circle
			(at 2.802636 2.032254)
			(size 0.381 0.381)
			(layers "F.Cu" "F.Mask" "F.Paste")
			(net "P5E_CPU1_P2_RX_DN<10>")
		)
		(pad "BK1" smd oval
			(at 2.649982 -3.938524)
			(size 0.254 0.3302)
			(layers "F.Cu" "F.Mask" "F.Paste")
			(net "P5E_CPU1_P2_RX_BUF_DP<10>")
		)
		(pad "BK35" smd oval
			(at 2.649982 3.940048)
			(size 0.254 0.3302)
			(layers "F.Cu" "F.Mask" "F.Paste")
			(net "P5E_CPU1_P2_TX_C_DP<10>")
		)
		(pad "BL4" smd circle
			(at 2.402586 -2.817368)
			(size 0.381 0.381)
			(layers "F.Cu" "F.Mask" "F.Paste")
			(net "GND")
		)
		(pad "BL13" smd circle
			(at 2.402586 -0.79629)
			(size 0.3048 0.3048)
			(layers "F.Cu" "F.Mask" "F.Paste")
			(net "GND")
		)
		(pad "BL17" smd circle
			(at 2.402586 -0.296164)
			(size 0.3048 0.3048)
			(layers "F.Cu" "F.Mask" "F.Paste")
			(net "P0V9_CPU1_RT_2D")
		)
		(pad "BL20" smd circle
			(at 2.402586 0.203708)
			(size 0.3048 0.3048)
			(layers "F.Cu" "F.Mask" "F.Paste")
			(net "P0V9_CPU1_RT_2D")
		)
		(pad "BL22" smd circle
			(at 2.402586 0.703834)
			(size 0.3048 0.3048)
			(layers "F.Cu" "F.Mask" "F.Paste")
			(net "GND")
		)
		(pad "BL32" smd circle
			(at 2.402586 2.724912)
			(size 0.381 0.381)
			(layers "F.Cu" "F.Mask" "F.Paste")
			(net "GND")
		)
		(pad "BM2" smd circle
			(at 2.350008 -3.41884)
			(size 0.3048 0.3048)
			(layers "F.Cu" "F.Mask" "F.Paste")
			(net "GND")
		)
		(pad "BM34" smd circle
			(at 2.350008 3.420364)
			(size 0.3048 0.3048)
			(layers "F.Cu" "F.Mask" "F.Paste")
			(net "GND")
		)
		(pad "BN1" smd oval
			(at 2.050034 -3.938524)
			(size 0.254 0.3302)
			(layers "F.Cu" "F.Mask" "F.Paste")
			(net "GND")
		)
		(pad "BN35" smd oval
			(at 2.050034 3.940048)
			(size 0.254 0.3302)
			(layers "F.Cu" "F.Mask" "F.Paste")
			(net "GND")
		)
		(pad "BP7" smd circle
			(at 2.002536 -2.12471)
			(size 0.381 0.381)
			(layers "F.Cu" "F.Mask" "F.Paste")
			(net "P5E_CPU1_P2_TX_BUF_DP<9>")
		)
		(pad "BP26" smd circle
			(at 2.002536 1.339342)
			(size 0.381 0.381)
			(layers "F.Cu" "F.Mask" "F.Paste")
			(net "P5E_CPU1_P2_RX_DP<9>")
		)
		(pad "BR2" smd circle
			(at 1.75006 -3.41884)
			(size 0.3048 0.3048)
			(layers "F.Cu" "F.Mask" "F.Paste")
			(net "P5E_CPU1_P2_RX_BUF_DN<9>")
		)
		(pad "BR34" smd circle
			(at 1.75006 3.420364)
			(size 0.3048 0.3048)
			(layers "F.Cu" "F.Mask" "F.Paste")
			(net "P5E_CPU1_P2_TX_C_DN<9>")
		)
		(pad "BT10" smd circle
			(at 1.602486 -1.431798)
			(size 0.381 0.381)
			(layers "F.Cu" "F.Mask" "F.Paste")
			(net "P5E_CPU1_P2_TX_BUF_DN<9>")
		)
		(pad "BT29" smd circle
			(at 1.602486 2.032254)
			(size 0.381 0.381)
			(layers "F.Cu" "F.Mask" "F.Paste")
			(net "P5E_CPU1_P2_RX_DN<9>")
		)
		(pad "BU1" smd oval
			(at 1.450086 -3.938524)
			(size 0.254 0.3302)
			(layers "F.Cu" "F.Mask" "F.Paste")
			(net "P5E_CPU1_P2_RX_BUF_DP<9>")
		)
		(pad "BU35" smd oval
			(at 1.450086 3.940048)
			(size 0.254 0.3302)
			(layers "F.Cu" "F.Mask" "F.Paste")
			(net "P5E_CPU1_P2_TX_C_DP<9>")
		)
		(pad "BV4" smd circle
			(at 1.20269 -2.817368)
			(size 0.381 0.381)
			(layers "F.Cu" "F.Mask" "F.Paste")
			(net "GND")
		)
		(pad "BV13" smd circle
			(at 1.20269 -0.79629)
			(size 0.3048 0.3048)
			(layers "F.Cu" "F.Mask" "F.Paste")
			(net "GND")
		)
		(pad "BV17" smd circle
			(at 1.20269 -0.296164)
			(size 0.3048 0.3048)
			(layers "F.Cu" "F.Mask" "F.Paste")
			(net "P1V8_CPU1_RT2_1A_1D")
		)
		(pad "BV20" smd circle
			(at 1.20269 0.203708)
			(size 0.3048 0.3048)
			(layers "F.Cu" "F.Mask" "F.Paste")
			(net "P1V8_CPU1_RT2_1A")
		)
		(pad "BV22" smd circle
			(at 1.20269 0.703834)
			(size 0.3048 0.3048)
			(layers "F.Cu" "F.Mask" "F.Paste")
			(net "GND")
		)
	)
)
